# S9S_MB_2U (Grand Teton) — schematic netlist excerpt (pin names and nets, part order shuffled) for the footprints in the layout excerpt that follows; sources: Cadence DE-HDL packaged netlist, KiCad conversion of 03242023_DA0F0TMBIJ0_F0T_Motherboard_J_brd_V01_OCP.brd

R1908  Q_RES  1K 1% CHIP  pkg 0402LF  page 156 : A = P3V3_AUX ; B = OCP_SFF_PRSNT3_R_N
R3865  Q_RES  0 5% EMPTY  pkg 0402LF  page 250 : A = P12V_OCP_SFF_ISENSE_MAM_TIC ; B = P12V_OCP_SFF_ISENSE_TIC

(kicad_pcb
	(version 20260206)
	(generator "pcbnew")
	(generator_version "10.0")
	(general
		(thickness 1.6)
		(legacy_teardrops no)
	)
	(paper "A4")
	(title_block
		(title "03242023_DA0F0TMBIJ0_F0T_Motherboard_J_brd_V01_OCP.brd")
		(comment 1 "Grand Teton / footprints 502-503 of 6105")
	)
	(layers
		(0 "F.Cu" signal "TOP")
		(4 "In1.Cu" signal "GND")
		(6 "In2.Cu" signal "IN1")
		(8 "In3.Cu" signal "GND1")
		(10 "In4.Cu" signal "IN2")
		(12 "In5.Cu" signal "GND2")
		(14 "In6.Cu" signal "IN3")
		(16 "In7.Cu" signal "GND3")
		(18 "In8.Cu" signal "VCC")
		(20 "In9.Cu" signal "VCC1")
		(22 "In10.Cu" signal "GND4")
		(24 "In11.Cu" signal "IN4")
		(26 "In12.Cu" signal "GND5")
		(28 "In13.Cu" signal "IN5")
		(30 "In14.Cu" signal "GND6")
		(32 "In15.Cu" signal "IN6")
		(34 "In16.Cu" signal "GND7")
		(2 "B.Cu" signal "BOTTOM")
		(9 "F.Adhes" user "F.Adhesive")
		(11 "B.Adhes" user "B.Adhesive")
		(13 "F.Paste" user "Package Geometry/Pastemask Top")
		(15 "B.Paste" user "Package Geometry/Pastemask Bottom")
		(5 "F.SilkS" user "Ref Des/Silkscreen Top")
		(7 "B.SilkS" user "Ref Des/Silkscreen Bottom")
		(1 "F.Mask" user "Board Geometry/Soldermask Top")
		(3 "B.Mask" user "Board Geometry/Soldermask Bottom")
		(17 "Dwgs.User" user "User.Drawings")
		(19 "Cmts.User" user "User.Comments")
		(21 "Eco1.User" user "User.Eco1")
		(23 "Eco2.User" user "User.Eco2")
		(25 "Edge.Cuts" user "Board Geometry/Outline")
		(27 "Margin" user)
		(31 "F.CrtYd" user "Package Geometry/Place Bound Top")
		(29 "B.CrtYd" user "Package Geometry/Place Bound Bottom")
		(35 "F.Fab" user "Ref Des/Assembly Top")
		(33 "B.Fab" user "Ref Des/Assembly Bottom")
	)
	(footprint ""
		(layer "F.Cu")
		(at 453.719946 -102.598728)
		(property "Reference" "R1908"
			(at 0 0 0)
			(layer "F.SilkS")
			(hide yes)
			(effects
				(font
					(size 1.27 1.27)
				)
			)
		)
		(property "Value" ""
			(at 0 0 0)
			(layer "F.Fab")
			(effects
				(font
					(size 1.27 1.27)
				)
			)
		)
		(duplicate_pad_numbers_are_jumpers no)
		(fp_line
			(start -0.7874 -0.4064)
			(end 0.7874 -0.4064)
			(stroke
				(width 0.1524)
				(type default)
			)
			(layer "F.SilkS")
		)
		(fp_line
			(start -0.7874 0.4064)
			(end -0.7874 -0.4064)
			(stroke
				(width 0.1524)
				(type default)
			)
			(layer "F.SilkS")
		)
		(fp_line
			(start 0.7874 -0.4064)
			(end 0.7874 0.4064)
			(stroke
				(width 0.1524)
				(type default)
			)
			(layer "F.SilkS")
		)
		(fp_line
			(start 0.7874 0.4064)
			(end -0.7874 0.4064)
			(stroke
				(width 0.1524)
				(type default)
			)
			(layer "F.SilkS")
		)
		(fp_line
			(start -0.67945 -0.305054)
			(end -0.12065 -0.305054)
			(stroke
				(width 0.1)
				(type default)
			)
			(layer "F.Fab")
		)
		(fp_line
			(start -0.67945 0.3048)
			(end -0.67945 -0.305054)
			(stroke
				(width 0.1)
				(type default)
			)
			(layer "F.Fab")
		)
		(fp_line
			(start -0.12065 -0.305054)
			(end -0.12065 -0.2794)
			(stroke
				(width 0.1)
				(type default)
			)
			(layer "F.Fab")
		)
		(fp_line
			(start -0.12065 -0.2794)
			(end 0.12065 -0.2794)
			(stroke
				(width 0.1)
				(type default)
			)
			(layer "F.Fab")
		)
		(fp_line
			(start -0.12065 0.2794)
			(end -0.12065 0.3048)
			(stroke
				(width 0.1)
				(type default)
			)
			(layer "F.Fab")
		)
		(fp_line
			(start -0.12065 0.3048)
			(end -0.67945 0.3048)
			(stroke
				(width 0.1)
				(type default)
			)
			(layer "F.Fab")
		)
		(fp_line
			(start 0.120396 0.2794)
			(end -0.12065 0.2794)
			(stroke
				(width 0.1)
				(type default)
			)
			(layer "F.Fab")
		)
		(fp_line
			(start 0.120396 0.3048)
			(end 0.120396 0.2794)
			(stroke
				(width 0.1)
				(type default)
			)
			(layer "F.Fab")
		)
		(fp_line
			(start 0.12065 -0.3048)
			(end 0.67945 -0.3048)
			(stroke
				(width 0.1)
				(type default)
			)
			(layer "F.Fab")
		)
		(fp_line
			(start 0.12065 -0.2794)
			(end 0.12065 -0.3048)
			(stroke
				(width 0.1)
				(type default)
			)
			(layer "F.Fab")
		)
		(fp_line
			(start 0.67945 -0.3048)
			(end 0.67945 0.3048)
			(stroke
				(width 0.1)
				(type default)
			)
			(layer "F.Fab")
		)
		(fp_line
			(start 0.67945 0.3048)
			(end 0.120396 0.3048)
			(stroke
				(width 0.1)
				(type default)
			)
			(layer "F.Fab")
		)
		(pad "1" smd circle
			(at -0.40005 0)
			(size 0 0)
			(layers "F.Cu" "F.Mask" "F.Paste")
			(net "P3V3_AUX")
		)
		(pad "2" smd circle
			(at 0.40005 0)
			(size 0 0)
			(layers "F.Cu" "F.Mask" "F.Paste")
			(net "OCP_SFF_PRSNT3_R_N")
		)
	)
	(footprint ""
		(layer "F.Cu")
		(at 40.627554 -111.606838 180)
		(property "Reference" "R3865"
			(at 0 0 180)
			(layer "F.SilkS")
			(hide yes)
			(effects
				(font
					(size 1.27 1.27)
				)
			)
		)
		(property "Value" ""
			(at 0 0 180)
			(layer "F.Fab")
			(effects
				(font
					(size 1.27 1.27)
				)
			)
		)
		(duplicate_pad_numbers_are_jumpers no)
		(fp_line
			(start 0.7874 0.4064)
			(end -0.7874 0.4064)
			(stroke
				(width 0.1524)
				(type default)
			)
			(layer "F.SilkS")
		)
		(fp_line
			(start 0.7874 -0.4064)
			(end 0.7874 0.4064)
			(stroke
				(width 0.1524)
				(type default)
			)
			(layer "F.SilkS")
		)
		(fp_line
			(start -0.7874 0.4064)
			(end -0.7874 -0.4064)
			(stroke
				(width 0.1524)
				(type default)
			)
			(layer "F.SilkS")
		)
		(fp_line
			(start -0.7874 -0.4064)
			(end 0.7874 -0.4064)
			(stroke
				(width 0.1524)
				(type default)
			)
			(layer "F.SilkS")
		)
		(fp_line
			(start 0.67945 0.3048)
			(end 0.120396 0.3048)
			(stroke
				(width 0.1)
				(type default)
			)
			(layer "F.Fab")
		)
		(fp_line
			(start 0.67945 -0.3048)
			(end 0.67945 0.3048)
			(stroke
				(width 0.1)
				(type default)
			)
			(layer "F.Fab")
		)
		(fp_line
			(start 0.12065 -0.2794)
			(end 0.12065 -0.3048)
			(stroke
				(width 0.1)
				(type default)
			)
			(layer "F.Fab")
		)
		(fp_line
			(start 0.12065 -0.3048)
			(end 0.67945 -0.3048)
			(stroke
				(width 0.1)
				(type default)
			)
			(layer "F.Fab")
		)
		(fp_line
			(start 0.120396 0.3048)
			(end 0.120396 0.2794)
			(stroke
				(width 0.1)
				(type default)
			)
			(layer "F.Fab")
		)
		(fp_line
			(start 0.120396 0.2794)
			(end -0.12065 0.2794)
			(stroke
				(width 0.1)
				(type default)
			)
			(layer "F.Fab")
		)
		(fp_line
			(start -0.12065 0.3048)
			(end -0.67945 0.3048)
			(stroke
				(width 0.1)
				(type default)
			)
			(layer "F.Fab")
		)
		(fp_line
			(start -0.12065 0.2794)
			(end -0.12065 0.3048)
			(stroke
				(width 0.1)
				(type default)
			)
			(layer "F.Fab")
		)
		(fp_line
			(start -0.12065 -0.2794)
			(end 0.12065 -0.2794)
			(stroke
				(width 0.1)
				(type default)
			)
			(layer "F.Fab")
		)
		(fp_line
			(start -0.12065 -0.305054)
			(end -0.12065 -0.2794)
			(stroke
				(width 0.1)
				(type default)
			)
			(layer "F.Fab")
		)
		(fp_line
			(start -0.67945 0.3048)
			(end -0.67945 -0.305054)
			(stroke
				(width 0.1)
				(type default)
			)
			(layer "F.Fab")
		)
		(fp_line
			(start -0.67945 -0.305054)
			(end -0.12065 -0.305054)
			(stroke
				(width 0.1)
				(type default)
			)
			(layer "F.Fab")
		)
		(pad "1" smd rect
			(at -0.40005 0)
			(size 0.4572 0.508)
			(layers "F.Cu" "F.Mask" "F.Paste")
			(net "P12V_OCP_SFF_ISENSE_MAM_TIC")
		)
		(pad "2" smd rect
			(at 0.40005 0)
			(size 0.4572 0.508)
			(layers "F.Cu" "F.Mask" "F.Paste")
			(net "P12V_OCP_SFF_ISENSE_TIC")
		)
	)
)
